#ISCELL
  mstr_symbols cad_note *
  *
#ISCELL
  mstr_symbols design_note *
  *
#ISCELL
  mstr_symbols intel_corp_bpage *
  *
#ISCELL
  mstr_standard offpage *
  page120_i10
#ISCELL
  mstr_standard offpage *
  page120_i111
#ISCELL
  mstr_standard offpage *
  page120_i113
#ISCELL
  mstr_standard offpage *
  page120_i115
#ISCELL
  mstr_standard offpage *
  page120_i116
#ISCELL
  mstr_standard offpage *
  page120_i117
#ISCELL
  mstr_standard offpage *
  page120_i118
#ISCELL
  mstr_standard offpage *
  page120_i119
#ISCELL
  mstr_standard offpage *
  page120_i140
#ISCELL
  mstr_standard offpage *
  page120_i141
#ISCELL
  mstr_standard offpage *
  page120_i142
#ISCELL
  mstr_standard offpage *
  page120_i143
#ISCELL
  mstr_standard offpage *
  page120_i145
#ISCELL
  mstr_standard offpage *
  page120_i146
#CELL
  mstr_u_proc lbg_core_qat_ext_d *
  page120_i147
#CELL
  mstr_discrete res *
  page120_i148
#ISCELL
  mstr_standard offpage *
  page120_i15
#ISCELL
  mstr_standard offpage *
  page120_i150
#ISCELL
  mstr_standard offpage *
  page120_i151
#ISCELL
  mstr_standard offpage *
  page120_i152
#ISCELL
  mstr_standard offpage *
  page120_i154
#ISCELL
  mstr_standard offpage *
  page120_i155
#ISCELL
  mstr_standard offpage *
  page120_i156
#ISCELL
  mstr_standard offpage *
  page120_i157
#ISCELL
  mstr_standard offpage *
  page120_i158
#ISCELL
  mstr_standard offpage *
  page120_i159
#ISCELL
  mstr_standard offpage *
  page120_i16
#ISCELL
  mstr_standard offpage *
  page120_i160
#ISCELL
  mstr_standard offpage *
  page120_i161
#ISCELL
  mstr_standard offpage *
  page120_i162
#ISCELL
  mstr_standard offpage *
  page120_i163
#ISCELL
  mstr_standard offpage *
  page120_i164
#ISCELL
  mstr_standard offpage *
  page120_i165
#ISCELL
  mstr_standard offpage *
  page120_i166
#ISCELL
  mstr_standard offpage *
  page120_i167
#ISCELL
  mstr_standard offpage *
  page120_i168
#ISCELL
  mstr_standard offpage *
  page120_i169
#ISCELL
  mstr_standard offpage *
  page120_i170
#ISCELL
  mstr_standard offpage *
  page120_i173
#ISCELL
  mstr_standard offpage *
  page120_i174
#ISCELL
  mstr_standard offpage *
  page120_i175
#ISCELL
  mstr_standard offpage *
  page120_i176
#ISCELL
  mstr_standard offpage *
  page120_i177
#ISCELL
  mstr_standard offpage *
  page120_i178
#ISCELL
  mstr_standard offpage *
  page120_i179
#ISCELL
  mstr_standard offpage *
  page120_i180
#ISCELL
  mstr_standard offpage *
  page120_i181
#ISCELL
  mstr_standard offpage *
  page120_i182
#ISCELL
  mstr_standard offpage *
  page120_i183
#ISCELL
  mstr_standard offpage *
  page120_i184
#ISCELL
  mstr_standard offpage *
  page120_i185
#ISCELL
  mstr_standard offpage *
  page120_i187
#ISCELL
  mstr_standard offpage *
  page120_i188
#ISCELL
  mstr_standard offpage *
  page120_i189
#ISCELL
  mstr_standard offpage *
  page120_i190
#ISCELL
  mstr_standard offpage *
  page120_i191
#ISCELL
  mstr_standard offpage *
  page120_i193
#ISCELL
  mstr_standard offpage *
  page120_i194
#ISCELL
  mstr_standard offpage *
  page120_i195
#ISCELL
  mstr_standard offpage *
  page120_i196
#ISCELL
  mstr_standard offpage *
  page120_i197
#ISCELL
  mstr_standard offpage *
  page120_i198
#ISCELL
  mstr_standard offpage *
  page120_i199
#ISCELL
  mstr_standard offpage *
  page120_i200
#ISCELL
  mstr_standard offpage *
  page120_i201
#ISCELL
  mstr_standard offpage *
  page120_i202
#ISCELL
  mstr_standard offpage *
  page120_i208
#ISCELL
  mstr_standard offpage *
  page120_i210
#ISCELL
  mstr_standard offpage *
  page120_i211
#ISCELL
  mstr_standard offpage *
  page120_i212
#ISCELL
  mstr_standard offpage *
  page120_i213
#ISCELL
  mstr_standard offpage *
  page120_i215
#ISCELL
  mstr_standard offpage *
  page120_i217
#CELL
  mstr_discrete res *
  page120_i218
#CELL
  mstr_discrete res *
  page120_i219
#ISCELL
  mstr_standard offpage *
  page120_i222
#ISCELL
  mstr_standard offpage *
  page120_i223
#ISCELL
  mstr_standard offpage *
  page120_i224
#ISCELL
  mstr_standard offpage *
  page120_i225
#ISCELL
  mstr_standard offpage *
  page120_i226
#ISCELL
  mstr_standard offpage *
  page120_i227
#ISCELL
  mstr_standard offpage *
  page120_i228
#ISCELL
  mstr_standard offpage *
  page120_i233
#ISCELL
  mstr_standard offpage *
  page120_i234
#ISCELL
  mstr_standard offpage *
  page120_i235
#ISCELL
  mstr_standard offpage *
  page120_i236
#ISCELL
  mstr_standard offpage *
  page120_i237
#ISCELL
  mstr_standard offpage *
  page120_i238
#ISCELL
  mstr_standard offpage *
  page120_i246
#ISCELL
  mstr_standard offpage *
  page120_i247
#ISCELL
  mstr_standard offpage *
  page120_i248
#ISCELL
  mstr_standard offpage *
  page120_i249
#ISCELL
  mstr_standard offpage *
  page120_i250
#ISCELL
  mstr_standard offpage *
  page120_i251
#ISCELL
  mstr_standard offpage *
  page120_i252
#ISCELL
  mstr_standard offpage *
  page120_i253
#ISCELL
  mstr_standard offpage *
  page120_i254
#ISCELL
  mstr_standard offpage *
  page120_i259
#ISCELL
  mstr_standard offpage *
  page120_i260
#ISCELL
  mstr_standard offpage *
  page120_i263
#ISCELL
  mstr_standard offpage *
  page120_i264
#ISCELL
  mstr_standard offpage *
  page120_i265
#ISCELL
  mstr_symbols gnd *
  page120_i266
#ISCELL
  mstr_standard offpage *
  page120_i4
#ISCELL
  mstr_standard offpage *
  page120_i43
#ISCELL
  mstr_standard offpage *
  page120_i5
#ISCELL
  mstr_standard offpage *
  page120_i53
#ISCELL
  mstr_standard offpage *
  page120_i54
#ISCELL
  mstr_standard offpage *
  page120_i68
#ISCELL
  mstr_standard offpage *
  page120_i69
#ISCELL
  mstr_standard offpage *
  page120_i7
#ISCELL
  mstr_standard offpage *
  page120_i70
#ISCELL
  mstr_standard offpage *
  page120_i71
#ISCELL
  mstr_standard offpage *
  page120_i72
#ISCELL
  mstr_standard offpage *
  page120_i73
#ISCELL
  mstr_standard offpage *
  page120_i74
#ISCELL
  mstr_standard offpage *
  page120_i75
#ISCELL
  mstr_standard offpage *
  page120_i76
#ISCELL
  mstr_standard offpage *
  page120_i77
#ISCELL
  mstr_standard offpage *
  page120_i9
